# BASEBOARD_FAB2 (Tioga Pass) — schematic netlist excerpt (pin names and nets, part order shuffled) for the footprints in the layout excerpt that follows; sources: Cadence DE-HDL packaged netlist, KiCad conversion of Wiwynn_Tioga_Pass_MB.brd

EU1E1  MOSFETN_1D3S  IC  pkg SOT5  page 200
  S1  = P12V_STBY
  S2  = P12V_STBY
  S3  = P12V_STBY
  G  = A_HSC_GATE3_R
  D  = P12V_MB0_SW

CT20  CAP  1000PF 50V 10% X7R  pkg 0402LF  page 208 : A = VR_PVCCIN_CPU1_PHASE4 ; B = VR_PVCCIN_CPU1_PHASE4_RC

(kicad_pcb
	(version 20260206)
	(generator "pcbnew")
	(generator_version "10.0")
	(general
		(thickness 1.6)
		(legacy_teardrops no)
	)
	(paper "A4")
	(title_block
		(title "Wiwynn_Tioga_Pass_MB.brd")
		(comment 1 "Tioga Pass / footprints 1263-1265 of 4770")
	)
	(layers
		(0 "F.Cu" signal "TOP")
		(4 "In1.Cu" signal "L2GND")
		(6 "In2.Cu" signal "L3")
		(8 "In3.Cu" signal "L4GND")
		(10 "In4.Cu" signal "L5")
		(12 "In5.Cu" signal "L6GND")
		(14 "In6.Cu" signal "L7VCC")
		(16 "In7.Cu" signal "L8VCC")
		(18 "In8.Cu" signal "L9GND")
		(20 "In9.Cu" signal "L10")
		(22 "In10.Cu" signal "L11GND")
		(24 "In11.Cu" signal "L12")
		(26 "In12.Cu" signal "L13GND")
		(2 "B.Cu" signal "BOTTOM")
		(9 "F.Adhes" user "F.Adhesive")
		(11 "B.Adhes" user "B.Adhesive")
		(13 "F.Paste" user "Package Geometry/Pastemask Top")
		(15 "B.Paste" user "Package Geometry/Pastemask Bottom")
		(5 "F.SilkS" user "Ref Des/Silkscreen Top")
		(7 "B.SilkS" user "Ref Des/Silkscreen Bottom")
		(1 "F.Mask" user "Board Geometry/Soldermask Top")
		(3 "B.Mask" user "Board Geometry/Soldermask Bottom")
		(17 "Dwgs.User" user "User.Drawings")
		(19 "Cmts.User" user "User.Comments")
		(21 "Eco1.User" user "User.Eco1")
		(23 "Eco2.User" user "User.Eco2")
		(25 "Edge.Cuts" user "Board Geometry/Outline")
		(27 "Margin" user)
		(31 "F.CrtYd" user "Package Geometry/Place Bound Top")
		(29 "B.CrtYd" user "Package Geometry/Place Bound Bottom")
		(35 "F.Fab" user "Ref Des/Assembly Top")
		(33 "B.Fab" user "Ref Des/Assembly Bottom")
	)
	(footprint ""
		(layer "F.Cu")
		(at 210.312 -106.045)
		(property "Reference" ""
			(at 0 0 0)
			(layer "F.SilkS")
			(hide yes)
			(effects
				(font
					(size 1.27 1.27)
				)
			)
		)
		(property "Value" ""
			(at 0 0 0)
			(layer "F.Fab")
			(effects
				(font
					(size 1.27 1.27)
				)
			)
		)
		(duplicate_pad_numbers_are_jumpers no)
		(fp_poly
			(pts
				(arc
					(start 2.032 0)
					(mid -2.032 0)
					(end 2.032 0)
				)
			)
			(stroke
				(width 0)
				(type default)
			)
			(fill no)
			(layer "F.CrtYd")
		)
		(pad "1" smd circle
			(at 0 0)
			(size 1.016 1.016)
			(layers "F.Cu" "F.Mask" "F.Paste")
			(net "Net_394")
		)
		(zone
			(layer "F.Cu")
			(hatch none 0.5)
			(connect_pads
				(clearance 0)
			)
			(min_thickness 0.25)
			(keepout
				(tracks not_allowed)
				(vias allowed)
				(pads allowed)
				(copperpour not_allowed)
				(footprints allowed)
			)
			(placement
				(enabled no)
				(sheetname "")
			)
			(fill
				(thermal_gap 0.5)
				(thermal_bridge_width 0.5)
				(island_removal_mode 0)
			)
			(polygon
				(pts
					(arc
						(start 211.836 -106.045)
						(mid 208.788 -106.045)
						(end 211.836 -106.045)
					)
				)
			)
		)
		(zone
			(layers "F.Cu" "B.Cu" "In1.Cu" "In2.Cu" "In3.Cu" "In4.Cu" "In5.Cu" "In6.Cu"
				"In7.Cu" "In8.Cu" "In9.Cu" "In10.Cu" "In11.Cu" "In12.Cu"
			)
			(hatch none 0.5)
			(connect_pads
				(clearance 0)
			)
			(min_thickness 0.25)
			(keepout
				(tracks allowed)
				(vias not_allowed)
				(pads allowed)
				(copperpour not_allowed)
				(footprints allowed)
			)
			(placement
				(enabled no)
				(sheetname "")
			)
			(fill
				(thermal_gap 0.5)
				(thermal_bridge_width 0.5)
				(island_removal_mode 0)
			)
			(polygon
				(pts
					(arc
						(start 211.836 -106.045)
						(mid 208.788 -106.045)
						(end 211.836 -106.045)
					)
				)
			)
		)
	)
	(footprint ""
		(layer "F.Cu")
		(at 39.1414 -77.7494 -90)
		(property "Reference" "CT20"
			(at -0.8382 -0.67818 270)
			(unlocked yes)
			(layer "F.SilkS")
			(effects
				(font
					(size 0.4064 0.254)
					(thickness 0.1524)
				)
				(justify left)
			)
		)
		(property "Value" ""
			(at 0 0 270)
			(layer "F.Fab")
			(effects
				(font
					(size 1.27 1.27)
				)
			)
		)
		(duplicate_pad_numbers_are_jumpers no)
		(fp_poly
			(pts
				(xy 0.3048 -0.1016) (xy 0.3048 0.9906) (xy -0.3048 0.9906) (xy -0.3048 -0.1016)
			)
			(stroke
				(width 0)
				(type default)
			)
			(fill no)
			(layer "F.CrtYd")
		)
		(fp_line
			(start -0.3048 0.9906)
			(end 0.3048 0.9906)
			(stroke
				(width 0.1)
				(type default)
			)
			(layer "F.Fab")
		)
		(fp_line
			(start 0.3048 0.9906)
			(end 0.3048 -0.1016)
			(stroke
				(width 0.1)
				(type default)
			)
			(layer "F.Fab")
		)
		(fp_line
			(start -0.3048 -0.1016)
			(end -0.3048 0.9906)
			(stroke
				(width 0.1)
				(type default)
			)
			(layer "F.Fab")
		)
		(fp_line
			(start 0.3048 -0.1016)
			(end -0.3048 -0.1016)
			(stroke
				(width 0.1)
				(type default)
			)
			(layer "F.Fab")
		)
		(pad "1" smd rect
			(at 0 0 270)
			(size 0.508 0.508)
			(layers "F.Cu" "F.Mask" "F.Paste")
			(net "VR_PVCCIN_CPU1_PHASE4")
		)
		(pad "2" smd rect
			(at 0 0.889 270)
			(size 0.508 0.508)
			(layers "F.Cu" "F.Mask" "F.Paste")
			(net "VR_PVCCIN_CPU1_PHASE4_RC")
		)
		(zone
			(layer "F.Cu")
			(hatch none 0.5)
			(connect_pads
				(clearance 0)
			)
			(min_thickness 0.25)
			(keepout
				(tracks not_allowed)
				(vias allowed)
				(pads allowed)
				(copperpour not_allowed)
				(footprints allowed)
			)
			(placement
				(enabled no)
				(sheetname "")
			)
			(fill
				(thermal_gap 0.5)
				(thermal_bridge_width 0.5)
				(island_removal_mode 0)
			)
			(polygon
				(pts
					(xy 38.5064 -78.0034) (xy 38.5064 -77.4954) (xy 38.8874 -77.4954) (xy 38.8874 -78.0034)
				)
			)
		)
		(zone
			(layer "F.Cu")
			(hatch none 0.5)
			(connect_pads
				(clearance 0)
			)
			(min_thickness 0.25)
			(keepout
				(tracks allowed)
				(vias not_allowed)
				(pads allowed)
				(copperpour not_allowed)
				(footprints allowed)
			)
			(placement
				(enabled no)
				(sheetname "")
			)
			(fill
				(thermal_gap 0.5)
				(thermal_bridge_width 0.5)
				(island_removal_mode 0)
			)
			(polygon
				(pts
					(xy 38.8874 -78.0034) (xy 38.8874 -77.4954) (xy 38.5064 -77.4954) (xy 38.5064 -78.0034)
				)
			)
		)
	)
	(footprint ""
		(layer "F.Cu")
		(at 21.082 -62.9158 180)
		(property "Reference" "EU1E1"
			(at 2.921 5.25653 0)
			(unlocked yes)
			(layer "F.SilkS")
			(effects
				(font
					(size 0.7874 0.5842)
					(thickness 0.1524)
				)
			)
		)
		(property "Value" ""
			(at 0 0 180)
			(layer "F.Fab")
			(effects
				(font
					(size 1.27 1.27)
				)
			)
		)
		(duplicate_pad_numbers_are_jumpers no)
		(fp_line
			(start 4.8006 4.5593)
			(end 4.8006 4.445254)
			(stroke
				(width 0.1524)
				(type default)
			)
			(layer "F.SilkS")
		)
		(fp_line
			(start 4.8006 -0.7493)
			(end 4.8006 -0.635254)
			(stroke
				(width 0.1524)
				(type default)
			)
			(layer "F.SilkS")
		)
		(fp_line
			(start 0.4064 4.5593)
			(end 4.8006 4.5593)
			(stroke
				(width 0.1524)
				(type default)
			)
			(layer "F.SilkS")
		)
		(fp_line
			(start 0.4064 4.445254)
			(end 0.4064 4.5593)
			(stroke
				(width 0.1524)
				(type default)
			)
			(layer "F.SilkS")
		)
		(fp_line
			(start 0.4064 -0.635254)
			(end 0.4064 -0.7493)
			(stroke
				(width 0.1524)
				(type default)
			)
			(layer "F.SilkS")
		)
		(fp_line
			(start 0.4064 -0.7493)
			(end 4.8006 -0.7493)
			(stroke
				(width 0.1524)
				(type default)
			)
			(layer "F.SilkS")
		)
		(fp_circle
			(center -0.682244 -0.831342)
			(end -0.809244 -0.831342)
			(stroke
				(width 0.254)
				(type default)
			)
			(fill no)
			(layer "F.SilkS")
		)
		(fp_rect
			(start 4.8006 4.5593)
			(end 0.4064 -0.7493)
			(stroke
				(width 0)
				(type default)
			)
			(fill no)
			(layer "F.CrtYd")
		)
		(fp_line
			(start 4.8006 4.5593)
			(end 0.4064 4.5593)
			(stroke
				(width 0.1)
				(type default)
			)
			(layer "F.Fab")
		)
		(fp_line
			(start 4.8006 -0.7493)
			(end 4.8006 4.5593)
			(stroke
				(width 0.1)
				(type default)
			)
			(layer "F.Fab")
		)
		(fp_line
			(start 0.4064 4.5593)
			(end 0.4064 -0.7493)
			(stroke
				(width 0.1)
				(type default)
			)
			(layer "F.Fab")
		)
		(fp_line
			(start 0.4064 -0.7493)
			(end 4.8006 -0.7493)
			(stroke
				(width 0.1)
				(type default)
			)
			(layer "F.Fab")
		)
		(fp_circle
			(center -1.076706 -0.704342)
			(end -1.203706 -0.704342)
			(stroke
				(width 0.635)
				(type default)
			)
			(fill no)
			(layer "F.Fab")
		)
		(pad "1" smd rect
			(at 0 0 180)
			(size 1.651 0.508)
			(layers "F.Cu" "F.Mask" "F.Paste")
			(net "P12V_STBY")
		)
		(pad "2" smd rect
			(at 0 1.27 180)
			(size 1.651 0.508)
			(layers "F.Cu" "F.Mask" "F.Paste")
			(net "P12V_STBY")
		)
		(pad "3" smd rect
			(at 0 2.54 180)
			(size 1.651 0.508)
			(layers "F.Cu" "F.Mask" "F.Paste")
			(net "P12V_STBY")
		)
		(pad "4" smd rect
			(at 0 3.81 180)
			(size 1.651 0.508)
			(layers "F.Cu" "F.Mask" "F.Paste")
			(net "A_HSC_GATE3_R")
		)
		(pad "5" smd custom
			(at 3.937 1.905 180)
			(size 1.04775 1.04775)
			(layers "F.Cu" "F.Mask" "F.Paste")
			(net "P12V_MB0_SW")
			(options
				(clearance outline)
				(anchor circle)
			)
			(primitives
				(gr_poly
					(pts
						(xy -2.0955 -1.651) (xy -2.0955 1.651) (xy 0.4445 1.651) (xy 0.4445 2.2098) (xy 2.0955 2.2098)
						(xy 2.0955 -2.2098) (xy 0.4445 -2.2098) (xy 0.4445 -1.651)
					)
					(width 0)
					(fill yes)
				)
			)
		)
	)
)
